# BASEBOARD_FAB2 (Tioga Pass) — schematic netlist excerpt (pin names and nets, part order shuffled) for the footprints in the layout excerpt that follows; sources: Cadence DE-HDL packaged netlist, KiCad conversion of Wiwynn_Tioga_Pass_MB.brd

R6M4  RES  4.75K 1% CHIP  pkg 0402  page 94 : A = P3V3 ; B = H_CPU1_MEMKLM_MEMHOT
C22W1  SC22U16V5MX-4-GP  20%  pkg SMD-BCG5  page 225 : \1\ = VR_FET_SW_P12V_STBY_PVDDQ_GHJ ; \2\ = GND
C6L2  CAP_A  0.01UF 25V 10% X7R  pkg 0402V  page 98 : A = M_F_CPU_VREF ; B = GND

(kicad_pcb
	(version 20260206)
	(generator "pcbnew")
	(generator_version "10.0")
	(general
		(thickness 1.6)
		(legacy_teardrops no)
	)
	(paper "A4")
	(title_block
		(title "Wiwynn_Tioga_Pass_MB.brd")
		(comment 1 "Tioga Pass / footprints 4318-4320 of 4770")
	)
	(layers
		(0 "F.Cu" signal "TOP")
		(4 "In1.Cu" signal "L2GND")
		(6 "In2.Cu" signal "L3")
		(8 "In3.Cu" signal "L4GND")
		(10 "In4.Cu" signal "L5")
		(12 "In5.Cu" signal "L6GND")
		(14 "In6.Cu" signal "L7VCC")
		(16 "In7.Cu" signal "L8VCC")
		(18 "In8.Cu" signal "L9GND")
		(20 "In9.Cu" signal "L10")
		(22 "In10.Cu" signal "L11GND")
		(24 "In11.Cu" signal "L12")
		(26 "In12.Cu" signal "L13GND")
		(2 "B.Cu" signal "BOTTOM")
		(9 "F.Adhes" user "F.Adhesive")
		(11 "B.Adhes" user "B.Adhesive")
		(13 "F.Paste" user "Package Geometry/Pastemask Top")
		(15 "B.Paste" user "Package Geometry/Pastemask Bottom")
		(5 "F.SilkS" user "Ref Des/Silkscreen Top")
		(7 "B.SilkS" user "Ref Des/Silkscreen Bottom")
		(1 "F.Mask" user "Board Geometry/Soldermask Top")
		(3 "B.Mask" user "Board Geometry/Soldermask Bottom")
		(17 "Dwgs.User" user "User.Drawings")
		(19 "Cmts.User" user "User.Comments")
		(21 "Eco1.User" user "User.Eco1")
		(23 "Eco2.User" user "User.Eco2")
		(25 "Edge.Cuts" user "Board Geometry/Outline")
		(27 "Margin" user)
		(31 "F.CrtYd" user "Package Geometry/Place Bound Top")
		(29 "B.CrtYd" user "Package Geometry/Place Bound Bottom")
		(35 "F.Fab" user "Ref Des/Assembly Top")
		(33 "B.Fab" user "Ref Des/Assembly Bottom")
	)
	(footprint ""
		(layer "B.Cu")
		(at 172.847 -126.111)
		(property "Reference" "R6M4"
			(at 0 0 0)
			(layer "B.SilkS")
			(hide yes)
			(effects
				(font
					(size 1.27 1.27)
				)
				(justify mirror)
			)
		)
		(property "Value" ""
			(at 0 0 0)
			(layer "B.Fab")
			(effects
				(font
					(size 1.27 1.27)
				)
				(justify mirror)
			)
		)
		(duplicate_pad_numbers_are_jumpers no)
		(fp_poly
			(pts
				(xy 0.2794 -0.1016) (xy -0.2794 -0.1016) (xy -0.2794 0.9906) (xy 0.2794 0.9906)
			)
			(stroke
				(width 0)
				(type default)
			)
			(fill no)
			(layer "B.CrtYd")
		)
		(fp_line
			(start -0.2794 -0.1016)
			(end 0.2794 -0.1016)
			(stroke
				(width 0.1)
				(type default)
			)
			(layer "B.Fab")
		)
		(fp_line
			(start -0.2794 0.9906)
			(end -0.2794 -0.1016)
			(stroke
				(width 0.1)
				(type default)
			)
			(layer "B.Fab")
		)
		(fp_line
			(start 0.2794 -0.1016)
			(end 0.2794 0.9906)
			(stroke
				(width 0.1)
				(type default)
			)
			(layer "B.Fab")
		)
		(fp_line
			(start 0.2794 0.9906)
			(end -0.2794 0.9906)
			(stroke
				(width 0.1)
				(type default)
			)
			(layer "B.Fab")
		)
		(pad "1" smd rect
			(at 0 0 180)
			(size 0.508 0.508)
			(layers "B.Cu" "B.Mask" "B.Paste")
			(net "P3V3")
		)
		(pad "2" smd rect
			(at 0 0.889 180)
			(size 0.508 0.508)
			(layers "B.Cu" "B.Mask" "B.Paste")
			(net "H_CPU1_MEMKLM_MEMHOT")
		)
		(zone
			(layer "B.Cu")
			(hatch none 0.5)
			(connect_pads
				(clearance 0)
			)
			(min_thickness 0.25)
			(keepout
				(tracks allowed)
				(vias not_allowed)
				(pads allowed)
				(copperpour not_allowed)
				(footprints allowed)
			)
			(placement
				(enabled no)
				(sheetname "")
			)
			(fill
				(thermal_gap 0.5)
				(thermal_bridge_width 0.5)
				(island_removal_mode 0)
			)
			(polygon
				(pts
					(xy 173.101 -125.857) (xy 172.593 -125.857) (xy 172.593 -125.476) (xy 173.101 -125.476)
				)
			)
		)
		(zone
			(layer "B.Cu")
			(hatch none 0.5)
			(connect_pads
				(clearance 0)
			)
			(min_thickness 0.25)
			(keepout
				(tracks not_allowed)
				(vias allowed)
				(pads allowed)
				(copperpour not_allowed)
				(footprints allowed)
			)
			(placement
				(enabled no)
				(sheetname "")
			)
			(fill
				(thermal_gap 0.5)
				(thermal_bridge_width 0.5)
				(island_removal_mode 0)
			)
			(polygon
				(pts
					(xy 173.101 -125.476) (xy 172.593 -125.476) (xy 172.593 -125.857) (xy 173.101 -125.857)
				)
			)
		)
	)
	(footprint ""
		(layer "B.Cu")
		(at -3.0226 -9.017 -90)
		(property "Reference" "C22W1"
			(at 0 0 90)
			(layer "B.SilkS")
			(hide yes)
			(effects
				(font
					(size 1.27 1.27)
				)
				(justify mirror)
			)
		)
		(property "Value" "*"
			(at 0.0762 -6.2357 270)
			(unlocked yes)
			(layer "B.Fab")
			(hide yes)
			(effects
				(font
					(size 1.27 1.016)
					(thickness 0.1524)
				)
				(justify mirror)
			)
		)
		(property "Device Type" "SC22U16V5MX-4-GP_SMD-BCG5-SC22A"
			(at 0.0762 -8.2677 270)
			(unlocked yes)
			(layer "B.Fab")
			(hide yes)
			(effects
				(font
					(size 1.27 1.016)
					(thickness 0.1524)
				)
				(justify mirror)
			)
		)
		(duplicate_pad_numbers_are_jumpers no)
		(fp_line
			(start -0.635 0)
			(end 0.635 0)
			(stroke
				(width 0.508)
				(type default)
			)
			(layer "B.SilkS")
		)
		(fp_rect
			(start 0.9652 1.778)
			(end -0.9652 -1.778)
			(stroke
				(width 0)
				(type default)
			)
			(fill no)
			(layer "B.CrtYd")
		)
		(fp_poly
			(pts
				(xy 0.9652 -1.778) (xy -0.9652 -1.778) (xy -0.9652 1.778) (xy 0.9652 1.778)
			)
			(stroke
				(width 0)
				(type default)
			)
			(fill no)
			(layer "B.Fab")
		)
		(pad "1" smd rect
			(at 0 -0.9652 90)
			(size 1.397 1.143)
			(layers "B.Cu" "B.Mask" "B.Paste")
			(net "VR_FET_SW_P12V_STBY_PVDDQ_GHJ")
		)
		(pad "2" smd rect
			(at 0 0.9652 90)
			(size 1.397 1.143)
			(layers "B.Cu" "B.Mask" "B.Paste")
			(net "GND")
		)
	)
	(footprint ""
		(layer "B.Cu")
		(at 191.897 -154.559 180)
		(property "Reference" "C6L2"
			(at 0 0 0)
			(layer "B.SilkS")
			(hide yes)
			(effects
				(font
					(size 1.27 1.27)
				)
				(justify mirror)
			)
		)
		(property "Value" ""
			(at 0 0 0)
			(layer "B.Fab")
			(effects
				(font
					(size 1.27 1.27)
				)
				(justify mirror)
			)
		)
		(duplicate_pad_numbers_are_jumpers no)
		(fp_poly
			(pts
				(xy -0.3048 -0.1016) (xy -0.3048 0.9906) (xy 0.3048 0.9906) (xy 0.3048 -0.1016)
			)
			(stroke
				(width 0)
				(type default)
			)
			(fill no)
			(layer "B.CrtYd")
		)
		(fp_line
			(start 0.3048 0.9906)
			(end -0.3048 0.9906)
			(stroke
				(width 0.1)
				(type default)
			)
			(layer "B.Fab")
		)
		(fp_line
			(start 0.3048 -0.1016)
			(end 0.3048 0.9906)
			(stroke
				(width 0.1)
				(type default)
			)
			(layer "B.Fab")
		)
		(fp_line
			(start -0.3048 0.9906)
			(end -0.3048 -0.1016)
			(stroke
				(width 0.1)
				(type default)
			)
			(layer "B.Fab")
		)
		(fp_line
			(start -0.3048 -0.1016)
			(end 0.3048 -0.1016)
			(stroke
				(width 0.1)
				(type default)
			)
			(layer "B.Fab")
		)
		(pad "1" smd rect
			(at 0 0)
			(size 0.508 0.508)
			(layers "B.Cu" "B.Mask" "B.Paste")
			(net "M_F_CPU_VREF")
		)
		(pad "2" smd rect
			(at 0 0.889)
			(size 0.508 0.508)
			(layers "B.Cu" "B.Mask" "B.Paste")
			(net "GND")
		)
		(zone
			(layer "B.Cu")
			(hatch none 0.5)
			(connect_pads
				(clearance 0)
			)
			(min_thickness 0.25)
			(keepout
				(tracks not_allowed)
				(vias allowed)
				(pads allowed)
				(copperpour not_allowed)
				(footprints allowed)
			)
			(placement
				(enabled no)
				(sheetname "")
			)
			(fill
				(thermal_gap 0.5)
				(thermal_bridge_width 0.5)
				(island_removal_mode 0)
			)
			(polygon
				(pts
					(xy 191.643 -155.194) (xy 192.151 -155.194) (xy 192.151 -154.813) (xy 191.643 -154.813)
				)
			)
		)
		(zone
			(layer "B.Cu")
			(hatch none 0.5)
			(connect_pads
				(clearance 0)
			)
			(min_thickness 0.25)
			(keepout
				(tracks allowed)
				(vias not_allowed)
				(pads allowed)
				(copperpour not_allowed)
				(footprints allowed)
			)
			(placement
				(enabled no)
				(sheetname "")
			)
			(fill
				(thermal_gap 0.5)
				(thermal_bridge_width 0.5)
				(island_removal_mode 0)
			)
			(polygon
				(pts
					(xy 191.643 -154.813) (xy 192.151 -154.813) (xy 192.151 -155.194) (xy 191.643 -155.194)
				)
			)
		)
	)
)
